# T6G (Grand Teton) — schematic netlist excerpt (pin names and nets, part order shuffled) for the footprints in the layout excerpt that follows; sources: Cadence DE-HDL packaged netlist, KiCad conversion of 04192023_DAF0TMB3IC0_F0TG_MB_C_brd_V02_OCP.brd

R3473  Q_RES  100K 1% EMPTY  pkg 0402LF  page 126 : A = GPU_PRSNT_N ; B = GND
R539  Q_RES  2.2K 5% CHIP  pkg 0402LF  page 54 : A = CPU1_XTRIG_L6 ; B = PVDD18_S5_P1

(kicad_pcb
	(version 20260206)
	(generator "pcbnew")
	(generator_version "10.0")
	(general
		(thickness 1.6)
		(legacy_teardrops no)
	)
	(paper "A4")
	(title_block
		(title "04192023_DAF0TMB3IC0_F0TG_MB_C_brd_V02_OCP.brd")
		(comment 1 "Grand Teton / footprints 6161-6162 of 8354")
	)
	(layers
		(0 "F.Cu" signal "TOP")
		(4 "In1.Cu" signal "GND")
		(6 "In2.Cu" signal "IN1")
		(8 "In3.Cu" signal "GND1")
		(10 "In4.Cu" signal "IN2")
		(12 "In5.Cu" signal "GND2")
		(14 "In6.Cu" signal "IN3")
		(16 "In7.Cu" signal "GND3")
		(18 "In8.Cu" signal "VCC")
		(20 "In9.Cu" signal "VCC1")
		(22 "In10.Cu" signal "GND4")
		(24 "In11.Cu" signal "IN4")
		(26 "In12.Cu" signal "GND5")
		(28 "In13.Cu" signal "IN5")
		(30 "In14.Cu" signal "GND6")
		(32 "In15.Cu" signal "IN6")
		(34 "In16.Cu" signal "GND7")
		(2 "B.Cu" signal "BOTTOM")
		(9 "F.Adhes" user "F.Adhesive")
		(11 "B.Adhes" user "B.Adhesive")
		(13 "F.Paste" user "Package Geometry/Pastemask Top")
		(15 "B.Paste" user "Package Geometry/Pastemask Bottom")
		(5 "F.SilkS" user "Ref Des/Silkscreen Top")
		(7 "B.SilkS" user "Ref Des/Silkscreen Bottom")
		(1 "F.Mask" user "Board Geometry/Soldermask Top")
		(3 "B.Mask" user "Board Geometry/Soldermask Bottom")
		(17 "Dwgs.User" user "User.Drawings")
		(19 "Cmts.User" user "User.Comments")
		(21 "Eco1.User" user "User.Eco1")
		(23 "Eco2.User" user "User.Eco2")
		(25 "Edge.Cuts" user "Board Geometry/Outline")
		(27 "Margin" user)
		(31 "F.CrtYd" user "Package Geometry/Place Bound Top")
		(29 "B.CrtYd" user "Package Geometry/Place Bound Bottom")
		(35 "F.Fab" user "Ref Des/Assembly Top")
		(33 "B.Fab" user "Ref Des/Assembly Bottom")
	)
	(footprint ""
		(layer "B.Cu")
		(at 90.503502 -205.14945 90)
		(property "Reference" "R539"
			(at 0 0 90)
			(layer "B.SilkS")
			(hide yes)
			(effects
				(font
					(size 1.27 1.27)
				)
				(justify mirror)
			)
		)
		(property "Value" ""
			(at 0 0 90)
			(layer "B.Fab")
			(effects
				(font
					(size 1.27 1.27)
				)
				(justify mirror)
			)
		)
		(duplicate_pad_numbers_are_jumpers no)
		(fp_line
			(start 0.7874 -0.4064)
			(end -0.7874 -0.4064)
			(stroke
				(width 0.1524)
				(type default)
			)
			(layer "B.SilkS")
		)
		(fp_line
			(start -0.7874 -0.4064)
			(end -0.7874 0.4064)
			(stroke
				(width 0.1524)
				(type default)
			)
			(layer "B.SilkS")
		)
		(fp_line
			(start 0.7874 0.4064)
			(end 0.7874 -0.4064)
			(stroke
				(width 0.1524)
				(type default)
			)
			(layer "B.SilkS")
		)
		(fp_line
			(start -0.7874 0.4064)
			(end 0.7874 0.4064)
			(stroke
				(width 0.1524)
				(type default)
			)
			(layer "B.SilkS")
		)
		(fp_line
			(start 0.67945 -0.305054)
			(end 0.12065 -0.305054)
			(stroke
				(width 0.1)
				(type default)
			)
			(layer "B.Fab")
		)
		(fp_line
			(start 0.12065 -0.305054)
			(end 0.12065 -0.2794)
			(stroke
				(width 0.1)
				(type default)
			)
			(layer "B.Fab")
		)
		(fp_line
			(start -0.12065 -0.3048)
			(end -0.67945 -0.3048)
			(stroke
				(width 0.1)
				(type default)
			)
			(layer "B.Fab")
		)
		(fp_line
			(start -0.67945 -0.3048)
			(end -0.67945 0.3048)
			(stroke
				(width 0.1)
				(type default)
			)
			(layer "B.Fab")
		)
		(fp_line
			(start 0.12065 -0.2794)
			(end -0.12065 -0.2794)
			(stroke
				(width 0.1)
				(type default)
			)
			(layer "B.Fab")
		)
		(fp_line
			(start -0.12065 -0.2794)
			(end -0.12065 -0.3048)
			(stroke
				(width 0.1)
				(type default)
			)
			(layer "B.Fab")
		)
		(fp_line
			(start 0.12065 0.2794)
			(end 0.12065 0.3048)
			(stroke
				(width 0.1)
				(type default)
			)
			(layer "B.Fab")
		)
		(fp_line
			(start -0.120396 0.2794)
			(end 0.12065 0.2794)
			(stroke
				(width 0.1)
				(type default)
			)
			(layer "B.Fab")
		)
		(fp_line
			(start 0.67945 0.3048)
			(end 0.67945 -0.305054)
			(stroke
				(width 0.1)
				(type default)
			)
			(layer "B.Fab")
		)
		(fp_line
			(start 0.12065 0.3048)
			(end 0.67945 0.3048)
			(stroke
				(width 0.1)
				(type default)
			)
			(layer "B.Fab")
		)
		(fp_line
			(start -0.120396 0.3048)
			(end -0.120396 0.2794)
			(stroke
				(width 0.1)
				(type default)
			)
			(layer "B.Fab")
		)
		(fp_line
			(start -0.67945 0.3048)
			(end -0.120396 0.3048)
			(stroke
				(width 0.1)
				(type default)
			)
			(layer "B.Fab")
		)
		(pad "1" smd circle
			(at 0.40005 0 270)
			(size 0 0)
			(layers "B.Cu" "B.Mask" "B.Paste")
			(net "CPU1_XTRIG_L6")
		)
		(pad "2" smd circle
			(at -0.40005 0 270)
			(size 0 0)
			(layers "B.Cu" "B.Mask" "B.Paste")
			(net "PVDD18_S5_P1")
		)
	)
	(footprint ""
		(layer "B.Cu")
		(at 51.766978 -429.84293 -90)
		(property "Reference" "R3473"
			(at 0 0 90)
			(layer "B.SilkS")
			(hide yes)
			(effects
				(font
					(size 1.27 1.27)
				)
				(justify mirror)
			)
		)
		(property "Value" ""
			(at 0 0 90)
			(layer "B.Fab")
			(effects
				(font
					(size 1.27 1.27)
				)
				(justify mirror)
			)
		)
		(duplicate_pad_numbers_are_jumpers no)
		(fp_line
			(start -0.7874 0.4064)
			(end 0.7874 0.4064)
			(stroke
				(width 0.1524)
				(type default)
			)
			(layer "B.SilkS")
		)
		(fp_line
			(start 0.7874 0.4064)
			(end 0.7874 -0.4064)
			(stroke
				(width 0.1524)
				(type default)
			)
			(layer "B.SilkS")
		)
		(fp_line
			(start -0.7874 -0.4064)
			(end -0.7874 0.4064)
			(stroke
				(width 0.1524)
				(type default)
			)
			(layer "B.SilkS")
		)
		(fp_line
			(start 0.7874 -0.4064)
			(end -0.7874 -0.4064)
			(stroke
				(width 0.1524)
				(type default)
			)
			(layer "B.SilkS")
		)
		(fp_line
			(start -0.67945 0.3048)
			(end -0.120396 0.3048)
			(stroke
				(width 0.1)
				(type default)
			)
			(layer "B.Fab")
		)
		(fp_line
			(start -0.120396 0.3048)
			(end -0.120396 0.2794)
			(stroke
				(width 0.1)
				(type default)
			)
			(layer "B.Fab")
		)
		(fp_line
			(start 0.12065 0.3048)
			(end 0.67945 0.3048)
			(stroke
				(width 0.1)
				(type default)
			)
			(layer "B.Fab")
		)
		(fp_line
			(start 0.67945 0.3048)
			(end 0.67945 -0.305054)
			(stroke
				(width 0.1)
				(type default)
			)
			(layer "B.Fab")
		)
		(fp_line
			(start -0.120396 0.2794)
			(end 0.12065 0.2794)
			(stroke
				(width 0.1)
				(type default)
			)
			(layer "B.Fab")
		)
		(fp_line
			(start 0.12065 0.2794)
			(end 0.12065 0.3048)
			(stroke
				(width 0.1)
				(type default)
			)
			(layer "B.Fab")
		)
		(fp_line
			(start -0.12065 -0.2794)
			(end -0.12065 -0.3048)
			(stroke
				(width 0.1)
				(type default)
			)
			(layer "B.Fab")
		)
		(fp_line
			(start 0.12065 -0.2794)
			(end -0.12065 -0.2794)
			(stroke
				(width 0.1)
				(type default)
			)
			(layer "B.Fab")
		)
		(fp_line
			(start -0.67945 -0.3048)
			(end -0.67945 0.3048)
			(stroke
				(width 0.1)
				(type default)
			)
			(layer "B.Fab")
		)
		(fp_line
			(start -0.12065 -0.3048)
			(end -0.67945 -0.3048)
			(stroke
				(width 0.1)
				(type default)
			)
			(layer "B.Fab")
		)
		(fp_line
			(start 0.12065 -0.305054)
			(end 0.12065 -0.2794)
			(stroke
				(width 0.1)
				(type default)
			)
			(layer "B.Fab")
		)
		(fp_line
			(start 0.67945 -0.305054)
			(end 0.12065 -0.305054)
			(stroke
				(width 0.1)
				(type default)
			)
			(layer "B.Fab")
		)
		(pad "1" smd circle
			(at 0.40005 0 90)
			(size 0 0)
			(layers "B.Cu" "B.Mask" "B.Paste")
			(net "GPU_PRSNT_N")
		)
		(pad "2" smd circle
			(at -0.40005 0 90)
			(size 0 0)
			(layers "B.Cu" "B.Mask" "B.Paste")
			(net "GND")
		)
	)
)
